(kicad_pcb
	(version 20260206)
	(generator "pcbnew")
	(generator_version "10.0")
	(general
		(thickness 1.6)
		(legacy_teardrops no)
	)
	(paper "A4")
	(title_block
		(title "netronome-mezz — pcbd0082-001_rev01_jul9_a.brd")
		(comment 1 "Open CloudServer (Microsoft) / footprints 534-541 of 714")
	)
	(layers
		(0 "F.Cu" signal "TOP")
		(4 "In1.Cu" signal "02_GND")
		(6 "In2.Cu" signal "03_SIG")
		(8 "In3.Cu" signal "04_SIG")
		(10 "In4.Cu" signal "05_GND")
		(12 "In5.Cu" signal "06_PWR1")
		(14 "In6.Cu" signal "07_SIG")
		(16 "In7.Cu" signal "08_SIG")
		(18 "In8.Cu" signal "09_GND")
		(2 "B.Cu" signal "BOTTOM")
		(9 "F.Adhes" user "F.Adhesive")
		(11 "B.Adhes" user "B.Adhesive")
		(13 "F.Paste" user "Package Geometry/Pastemask Top")
		(15 "B.Paste" user "Package Geometry/Pastemask Bottom")
		(5 "F.SilkS" user "Ref Des/Silkscreen Top")
		(7 "B.SilkS" user "Ref Des/Silkscreen Bottom")
		(1 "F.Mask" user "Board Geometry/Soldermask Top")
		(3 "B.Mask" user "Board Geometry/Soldermask Bottom")
		(17 "Dwgs.User" user "User.Drawings")
		(19 "Cmts.User" user "User.Comments")
		(21 "Eco1.User" user "User.Eco1")
		(23 "Eco2.User" user "User.Eco2")
		(25 "Edge.Cuts" user "Board Geometry/Outline")
		(27 "Margin" user)
		(31 "F.CrtYd" user "Package Geometry/Place Bound Top")
		(29 "B.CrtYd" user "Package Geometry/Place Bound Bottom")
		(35 "F.Fab" user "Ref Des/Assembly Top")
		(33 "B.Fab" user "Ref Des/Assembly Bottom")
		(45 "User.4" user "COMPVAL_TYPE_BOTTOM")
	)
	(footprint ""
		(layer "B.Cu")
		(at 33.655 22.733 -90)
		(property "Reference" "R398"
			(at 0 0 90)
			(layer "B.SilkS")
			(hide yes)
			(effects
				(font
					(size 1.27 1.27)
				)
				(justify mirror)
			)
		)
		(property "Value" "4.75K"
			(at 0.148158 1.3462 180)
			(unlocked yes)
			(layer "B.Fab")
			(hide yes)
			(effects
				(font
					(size 1.27 0.9652)
					(thickness 0.000001)
				)
				(justify left mirror)
			)
		)
		(property "Device Type" "REST4024"
			(at 0.148158 1.3462 180)
			(unlocked yes)
			(layer "B.Fab")
			(hide yes)
			(effects
				(font
					(size 1.27 0.9652)
					(thickness 0.000001)
				)
				(justify left mirror)
			)
		)
		(duplicate_pad_numbers_are_jumpers no)
		(fp_poly
			(pts
				(xy -0.635 1.0668) (xy -0.635 -1.0668) (xy 0.635 -1.0668) (xy 0.635 1.0668)
			)
			(stroke
				(width 0)
				(type default)
			)
			(fill no)
			(layer "B.CrtYd")
		)
		(fp_line
			(start -0.254 0.508)
			(end 0.254 0.508)
			(stroke
				(width 0.0254)
				(type default)
			)
			(layer "B.Fab")
		)
		(fp_line
			(start 0.254 0.508)
			(end 0.254 -0.508)
			(stroke
				(width 0.0254)
				(type default)
			)
			(layer "B.Fab")
		)
		(fp_line
			(start -0.254 -0.508)
			(end -0.254 0.508)
			(stroke
				(width 0.0254)
				(type default)
			)
			(layer "B.Fab")
		)
		(fp_line
			(start 0.254 -0.508)
			(end -0.254 -0.508)
			(stroke
				(width 0.0254)
				(type default)
			)
			(layer "B.Fab")
		)
		(pad "1" smd rect
			(at 0 -0.4191 90)
			(size 0.508 0.5334)
			(layers "B.Cu" "B.Mask" "B.Paste")
			(net "EXT_3.3V")
		)
		(pad "2" smd rect
			(at 0 0.4191 90)
			(size 0.508 0.5334)
			(layers "B.Cu" "B.Mask" "B.Paste")
			(net "CPLD_SMBUS_SDA")
		)
		(zone
			(layer "B.Cu")
			(hatch none 0.5)
			(connect_pads
				(clearance 0)
			)
			(min_thickness 0.25)
			(keepout
				(tracks not_allowed)
				(vias allowed)
				(pads allowed)
				(copperpour not_allowed)
				(footprints allowed)
			)
			(placement
				(enabled no)
				(sheetname "")
			)
			(fill
				(thermal_gap 0.5)
				(thermal_bridge_width 0.5)
				(island_removal_mode 0)
			)
			(polygon
				(pts
					(xy 33.6804 22.7076) (xy 33.6296 22.7076) (xy 33.6296 22.7584) (xy 33.6804 22.7584)
				)
			)
		)
	)
	(footprint ""
		(layer "B.Cu")
		(at 5.207 6.35)
		(property "Reference" "TP26"
			(at 1.24333 -0.762 270)
			(unlocked yes)
			(layer "B.SilkS")
			(effects
				(font
					(size 0.7874 0.5842)
					(thickness 0.127)
				)
				(justify left mirror)
			)
		)
		(property "Value" "*"
			(at 0.4826 -0.14732 0)
			(unlocked yes)
			(layer "B.Fab")
			(hide yes)
			(effects
				(font
					(size 1.27 0.9652)
					(thickness 0.000001)
				)
				(justify left mirror)
			)
		)
		(property "Device Type" "TP_SMALL"
			(at 0.4826 -0.14732 0)
			(unlocked yes)
			(layer "B.Fab")
			(hide yes)
			(effects
				(font
					(size 1.27 0.9652)
					(thickness 0.000001)
				)
				(justify left mirror)
			)
		)
		(duplicate_pad_numbers_are_jumpers no)
		(fp_line
			(start -0.8636 -0.8636)
			(end 0.8636 -0.8636)
			(stroke
				(width 0.1524)
				(type default)
			)
			(layer "B.SilkS")
		)
		(fp_line
			(start -0.8636 0.8636)
			(end -0.8636 -0.8636)
			(stroke
				(width 0.1524)
				(type default)
			)
			(layer "B.SilkS")
		)
		(fp_line
			(start 0.8636 -0.8636)
			(end 0.8636 0.8636)
			(stroke
				(width 0.1524)
				(type default)
			)
			(layer "B.SilkS")
		)
		(fp_line
			(start 0.8636 0.8636)
			(end -0.8636 0.8636)
			(stroke
				(width 0.1524)
				(type default)
			)
			(layer "B.SilkS")
		)
		(fp_poly
			(pts
				(xy 0.635 -0.635) (xy 0.635 0.635) (xy -0.635 0.635) (xy -0.635 -0.635)
			)
			(stroke
				(width 0)
				(type default)
			)
			(fill no)
			(layer "B.CrtYd")
		)
		(pad "1" smd rect
			(at 0 0 180)
			(size 1.27 1.27)
			(layers "B.Cu" "B.Mask" "B.Paste")
			(net "PGRM_JTAG_TRST_L")
		)
	)
	(footprint ""
		(layer "B.Cu")
		(at 59.236991 7.542022 180)
		(property "Reference" "C89"
			(at -0.045339 2.462022 270)
			(unlocked yes)
			(layer "B.SilkS")
			(effects
				(font
					(size 0.7874 0.5842)
					(thickness 0.127)
				)
				(justify mirror)
			)
		)
		(property "Value" ""
			(at 0 0 0)
			(layer "B.Fab")
			(effects
				(font
					(size 1.27 1.27)
				)
				(justify mirror)
			)
		)
		(duplicate_pad_numbers_are_jumpers no)
		(fp_circle
			(center 0 0)
			(end -0.104648 0)
			(stroke
				(width 0.1016)
				(type default)
			)
			(fill no)
			(layer "B.SilkS")
		)
		(fp_poly
			(pts
				(xy 0.381 -0.889) (xy 0.381 0.889) (xy -0.381 0.889) (xy -0.381 -0.889)
			)
			(stroke
				(width 0)
				(type default)
			)
			(fill no)
			(layer "B.CrtYd")
		)
		(fp_line
			(start 0.508 1.016)
			(end 0.508 -1.016)
			(stroke
				(width 0.0254)
				(type default)
			)
			(layer "B.Fab")
		)
		(fp_line
			(start 0.508 -1.016)
			(end 0.254 -1.016)
			(stroke
				(width 0.0254)
				(type default)
			)
			(layer "B.Fab")
		)
		(fp_line
			(start 0.254 -1.016)
			(end -0.508 -1.016)
			(stroke
				(width 0.0254)
				(type default)
			)
			(layer "B.Fab")
		)
		(fp_line
			(start -0.508 1.016)
			(end 0.508 1.016)
			(stroke
				(width 0.0254)
				(type default)
			)
			(layer "B.Fab")
		)
		(fp_line
			(start -0.508 -1.016)
			(end -0.508 1.016)
			(stroke
				(width 0.0254)
				(type default)
			)
			(layer "B.Fab")
		)
		(pad "1" smd custom
			(at 0 -0.500126)
			(size 0.127 0.127)
			(layers "B.Cu" "B.Mask" "B.Paste")
			(net "VDDA_PCIE0")
			(options
				(clearance outline)
				(anchor circle)
			)
			(primitives
				(gr_poly
					(pts
						(xy -0.1778 0.254) (xy 0.1778 0.254) (xy 0.254 0.1778) (xy 0.254 -0.1778) (xy 0.1778 -0.254) (xy -0.1778 -0.254)
						(xy -0.254 -0.1778) (xy -0.254 0.1778)
					)
					(width 0)
					(fill yes)
				)
			)
		)
		(pad "2" smd custom
			(at 0 0.500126)
			(size 0.127 0.127)
			(layers "B.Cu" "B.Mask" "B.Paste")
			(net "GND")
			(options
				(clearance outline)
				(anchor circle)
			)
			(primitives
				(gr_poly
					(pts
						(xy -0.1778 0.254) (xy 0.1778 0.254) (xy 0.254 0.1778) (xy 0.254 -0.1778) (xy 0.1778 -0.254) (xy -0.1778 -0.254)
						(xy -0.254 -0.1778) (xy -0.254 0.1778)
					)
					(width 0)
					(fill yes)
				)
			)
		)
	)
	(footprint ""
		(layer "B.Cu")
		(at 37.846 24.003 90)
		(property "Reference" "L14"
			(at -0.508 -0.78867 270)
			(unlocked yes)
			(layer "B.SilkS")
			(effects
				(font
					(size 0.7874 0.5842)
					(thickness 0.127)
				)
				(justify left mirror)
			)
		)
		(property "Value" ""
			(at 0 0 90)
			(layer "B.Fab")
			(effects
				(font
					(size 1.27 1.27)
				)
				(justify mirror)
			)
		)
		(duplicate_pad_numbers_are_jumpers no)
		(fp_line
			(start 0.0254 -0.127)
			(end -0.0254 -0.127)
			(stroke
				(width 0.1016)
				(type default)
			)
			(layer "B.SilkS")
		)
		(fp_line
			(start -0.0254 -0.127)
			(end -0.0254 0.127)
			(stroke
				(width 0.1016)
				(type default)
			)
			(layer "B.SilkS")
		)
		(fp_line
			(start 0.0254 0.127)
			(end 0.0254 -0.127)
			(stroke
				(width 0.1016)
				(type default)
			)
			(layer "B.SilkS")
		)
		(fp_line
			(start -0.0254 0.127)
			(end 0.0254 0.127)
			(stroke
				(width 0.1016)
				(type default)
			)
			(layer "B.SilkS")
		)
		(fp_poly
			(pts
				(xy -0.889 -0.4953) (xy -0.889 0.4953) (xy 0.889 0.4953) (xy 0.889 -0.4953)
			)
			(stroke
				(width 0)
				(type default)
			)
			(fill no)
			(layer "B.CrtYd")
		)
		(fp_line
			(start 0.508 -0.254)
			(end 0.508 0.254)
			(stroke
				(width 0.0254)
				(type default)
			)
			(layer "B.Fab")
		)
		(fp_line
			(start -0.508 -0.254)
			(end 0.508 -0.254)
			(stroke
				(width 0.0254)
				(type default)
			)
			(layer "B.Fab")
		)
		(fp_line
			(start 0.508 0.254)
			(end -0.508 0.254)
			(stroke
				(width 0.0254)
				(type default)
			)
			(layer "B.Fab")
		)
		(fp_line
			(start -0.508 0.254)
			(end -0.508 -0.254)
			(stroke
				(width 0.0254)
				(type default)
			)
			(layer "B.Fab")
		)
		(pad "1" smd rect
			(at 0.4699 0 270)
			(size 0.5334 0.508)
			(layers "B.Cu" "B.Mask" "B.Paste")
			(net "VDDA_TS0")
		)
		(pad "2" smd rect
			(at -0.4699 0 270)
			(size 0.5334 0.508)
			(layers "B.Cu" "B.Mask" "B.Paste")
			(net "VDD_1.5V")
		)
	)
	(footprint ""
		(layer "B.Cu")
		(at 65.8368 32.004 90)
		(property "Reference" "C68"
			(at 0.22733 4.826 0)
			(unlocked yes)
			(layer "B.SilkS")
			(effects
				(font
					(size 0.7874 0.5842)
					(thickness 0.127)
				)
				(justify left mirror)
			)
		)
		(property "Value" "100UF"
			(at 0.78232 0.4826 0)
			(unlocked yes)
			(layer "B.Fab")
			(hide yes)
			(effects
				(font
					(size 1.27 0.9652)
					(thickness 0.000001)
				)
				(justify left mirror)
			)
		)
		(property "Device Type" "CAPC0087"
			(at 0.78232 0.4826 0)
			(unlocked yes)
			(layer "B.Fab")
			(hide yes)
			(effects
				(font
					(size 1.27 0.9652)
					(thickness 0.000001)
				)
				(justify left mirror)
			)
		)
		(duplicate_pad_numbers_are_jumpers no)
		(fp_circle
			(center 0 0)
			(end 0 0.508)
			(stroke
				(width 0.2032)
				(type default)
			)
			(fill no)
			(layer "B.SilkS")
		)
		(fp_poly
			(pts
				(xy 1.27 2.9464) (xy -1.27 2.9464) (xy -1.27 -2.846095) (xy 1.27 -2.846095)
			)
			(stroke
				(width 0)
				(type default)
			)
			(fill no)
			(layer "B.CrtYd")
		)
		(fp_line
			(start 1.016 -2.794)
			(end -1.016 -2.794)
			(stroke
				(width 0.0254)
				(type default)
			)
			(layer "B.Fab")
		)
		(fp_line
			(start -1.016 -2.794)
			(end -1.016 2.794)
			(stroke
				(width 0.0254)
				(type default)
			)
			(layer "B.Fab")
		)
		(fp_line
			(start 1.016 2.794)
			(end 1.016 -2.794)
			(stroke
				(width 0.0254)
				(type default)
			)
			(layer "B.Fab")
		)
		(fp_line
			(start -1.016 2.794)
			(end 1.016 2.794)
			(stroke
				(width 0.0254)
				(type default)
			)
			(layer "B.Fab")
		)
		(pad "1" smd rect
			(at 0 -1.6764 270)
			(size 1.524 1.524)
			(layers "B.Cu" "B.Mask" "B.Paste")
			(net "DDR_VDDQ")
		)
		(pad "2" smd rect
			(at 0 1.6764 270)
			(size 1.524 1.524)
			(layers "B.Cu" "B.Mask" "B.Paste")
			(net "GND")
		)
		(zone
			(layer "B.Cu")
			(hatch none 0.5)
			(connect_pads
				(clearance 0)
			)
			(min_thickness 0.25)
			(keepout
				(tracks not_allowed)
				(vias allowed)
				(pads allowed)
				(copperpour not_allowed)
				(footprints allowed)
			)
			(placement
				(enabled no)
				(sheetname "")
			)
			(fill
				(thermal_gap 0.5)
				(thermal_bridge_width 0.5)
				(island_removal_mode 0)
			)
			(polygon
				(pts
					(xy 64.9478 31.2166) (xy 64.9478 32.7914) (xy 65.1002 32.7914) (xy 65.1002 31.2166)
				)
			)
		)
		(zone
			(layer "B.Cu")
			(hatch none 0.5)
			(connect_pads
				(clearance 0)
			)
			(min_thickness 0.25)
			(keepout
				(tracks not_allowed)
				(vias allowed)
				(pads allowed)
				(copperpour not_allowed)
				(footprints allowed)
			)
			(placement
				(enabled no)
				(sheetname "")
			)
			(fill
				(thermal_gap 0.5)
				(thermal_bridge_width 0.5)
				(island_removal_mode 0)
			)
			(polygon
				(pts
					(xy 66.5734 31.2166) (xy 66.5734 32.7914) (xy 66.7258 32.7914) (xy 66.7258 31.2166)
				)
			)
		)
		(zone
			(layer "B.Cu")
			(hatch none 0.5)
			(connect_pads
				(clearance 0)
			)
			(min_thickness 0.25)
			(keepout
				(tracks allowed)
				(vias not_allowed)
				(pads allowed)
				(copperpour not_allowed)
				(footprints allowed)
			)
			(placement
				(enabled no)
				(sheetname "")
			)
			(fill
				(thermal_gap 0.5)
				(thermal_bridge_width 0.5)
				(island_removal_mode 0)
			)
			(polygon
				(pts
					(xy 67.437 31.2166) (xy 67.437 32.7914) (xy 64.2366 32.7914) (xy 64.2366 31.2166)
				)
			)
		)
	)
	(footprint ""
		(layer "B.Cu")
		(at 22.733 30.861 -90)
		(property "Reference" "R89"
			(at -0.35433 0.889 0)
			(unlocked yes)
			(layer "B.SilkS")
			(effects
				(font
					(size 0.7874 0.5842)
					(thickness 0.127)
				)
				(justify left mirror)
			)
		)
		(property "Value" "4.75K"
			(at 0.148158 1.3462 180)
			(unlocked yes)
			(layer "B.Fab")
			(hide yes)
			(effects
				(font
					(size 1.27 0.9652)
					(thickness 0.000001)
				)
				(justify left mirror)
			)
		)
		(property "Device Type" "REST4024"
			(at 0.148158 1.3462 180)
			(unlocked yes)
			(layer "B.Fab")
			(hide yes)
			(effects
				(font
					(size 1.27 0.9652)
					(thickness 0.000001)
				)
				(justify left mirror)
			)
		)
		(duplicate_pad_numbers_are_jumpers no)
		(fp_poly
			(pts
				(xy -0.635 1.0668) (xy -0.635 -1.0668) (xy 0.635 -1.0668) (xy 0.635 1.0668)
			)
			(stroke
				(width 0)
				(type default)
			)
			(fill no)
			(layer "B.CrtYd")
		)
		(fp_line
			(start -0.254 0.508)
			(end 0.254 0.508)
			(stroke
				(width 0.0254)
				(type default)
			)
			(layer "B.Fab")
		)
		(fp_line
			(start 0.254 0.508)
			(end 0.254 -0.508)
			(stroke
				(width 0.0254)
				(type default)
			)
			(layer "B.Fab")
		)
		(fp_line
			(start -0.254 -0.508)
			(end -0.254 0.508)
			(stroke
				(width 0.0254)
				(type default)
			)
			(layer "B.Fab")
		)
		(fp_line
			(start 0.254 -0.508)
			(end -0.254 -0.508)
			(stroke
				(width 0.0254)
				(type default)
			)
			(layer "B.Fab")
		)
		(pad "1" smd rect
			(at 0 -0.4191 90)
			(size 0.508 0.5334)
			(layers "B.Cu" "B.Mask" "B.Paste")
			(net "CPLD_CORE_PSI_L")
		)
		(pad "2" smd rect
			(at 0 0.4191 90)
			(size 0.508 0.5334)
			(layers "B.Cu" "B.Mask" "B.Paste")
			(net "VDD_3.3V")
		)
		(zone
			(layer "B.Cu")
			(hatch none 0.5)
			(connect_pads
				(clearance 0)
			)
			(min_thickness 0.25)
			(keepout
				(tracks not_allowed)
				(vias allowed)
				(pads allowed)
				(copperpour not_allowed)
				(footprints allowed)
			)
			(placement
				(enabled no)
				(sheetname "")
			)
			(fill
				(thermal_gap 0.5)
				(thermal_bridge_width 0.5)
				(island_removal_mode 0)
			)
			(polygon
				(pts
					(xy 22.7584 30.8356) (xy 22.7076 30.8356) (xy 22.7076 30.8864) (xy 22.7584 30.8864)
				)
			)
		)
	)
	(footprint ""
		(layer "B.Cu")
		(at 33.655 21.844 -90)
		(property "Reference" "R397"
			(at -0.86233 -0.762 0)
			(unlocked yes)
			(layer "B.SilkS")
			(effects
				(font
					(size 0.7874 0.5842)
					(thickness 0.127)
				)
				(justify left mirror)
			)
		)
		(property "Value" "4.75K"
			(at 0.148158 1.3462 180)
			(unlocked yes)
			(layer "B.Fab")
			(hide yes)
			(effects
				(font
					(size 1.27 0.9652)
					(thickness 0.000001)
				)
				(justify left mirror)
			)
		)
		(property "Device Type" "REST4024"
			(at 0.148158 1.3462 180)
			(unlocked yes)
			(layer "B.Fab")
			(hide yes)
			(effects
				(font
					(size 1.27 0.9652)
					(thickness 0.000001)
				)
				(justify left mirror)
			)
		)
		(duplicate_pad_numbers_are_jumpers no)
		(fp_poly
			(pts
				(xy -0.635 1.0668) (xy -0.635 -1.0668) (xy 0.635 -1.0668) (xy 0.635 1.0668)
			)
			(stroke
				(width 0)
				(type default)
			)
			(fill no)
			(layer "B.CrtYd")
		)
		(fp_line
			(start -0.254 0.508)
			(end 0.254 0.508)
			(stroke
				(width 0.0254)
				(type default)
			)
			(layer "B.Fab")
		)
		(fp_line
			(start 0.254 0.508)
			(end 0.254 -0.508)
			(stroke
				(width 0.0254)
				(type default)
			)
			(layer "B.Fab")
		)
		(fp_line
			(start -0.254 -0.508)
			(end -0.254 0.508)
			(stroke
				(width 0.0254)
				(type default)
			)
			(layer "B.Fab")
		)
		(fp_line
			(start 0.254 -0.508)
			(end -0.254 -0.508)
			(stroke
				(width 0.0254)
				(type default)
			)
			(layer "B.Fab")
		)
		(pad "1" smd rect
			(at 0 -0.4191 90)
			(size 0.508 0.5334)
			(layers "B.Cu" "B.Mask" "B.Paste")
			(net "EXT_3.3V")
		)
		(pad "2" smd rect
			(at 0 0.4191 90)
			(size 0.508 0.5334)
			(layers "B.Cu" "B.Mask" "B.Paste")
			(net "CPLD_PCIE0_WAKE_L")
		)
		(zone
			(layer "B.Cu")
			(hatch none 0.5)
			(connect_pads
				(clearance 0)
			)
			(min_thickness 0.25)
			(keepout
				(tracks not_allowed)
				(vias allowed)
				(pads allowed)
				(copperpour not_allowed)
				(footprints allowed)
			)
			(placement
				(enabled no)
				(sheetname "")
			)
			(fill
				(thermal_gap 0.5)
				(thermal_bridge_width 0.5)
				(island_removal_mode 0)
			)
			(polygon
				(pts
					(xy 33.6804 21.8186) (xy 33.6296 21.8186) (xy 33.6296 21.8694) (xy 33.6804 21.8694)
				)
			)
		)
	)
	(footprint ""
		(layer "B.Cu")
		(at 51.237007 29.541978)
		(property "Reference" "C197"
			(at 0 0 0)
			(layer "B.SilkS")
			(hide yes)
			(effects
				(font
					(size 1.27 1.27)
				)
				(justify mirror)
			)
		)
		(property "Value" ""
			(at 0 0 0)
			(layer "B.Fab")
			(effects
				(font
					(size 1.27 1.27)
				)
				(justify mirror)
			)
		)
		(duplicate_pad_numbers_are_jumpers no)
		(fp_circle
			(center 0 0)
			(end 0.104648 0)
			(stroke
				(width 0.1016)
				(type default)
			)
			(fill no)
			(layer "B.SilkS")
		)
		(fp_poly
			(pts
				(xy 0.381 -0.889) (xy 0.381 0.889) (xy -0.381 0.889) (xy -0.381 -0.889)
			)
			(stroke
				(width 0)
				(type default)
			)
			(fill no)
			(layer "B.CrtYd")
		)
		(fp_line
			(start -0.508 -1.016)
			(end -0.508 1.016)
			(stroke
				(width 0.0254)
				(type default)
			)
			(layer "B.Fab")
		)
		(fp_line
			(start -0.508 1.016)
			(end 0.508 1.016)
			(stroke
				(width 0.0254)
				(type default)
			)
			(layer "B.Fab")
		)
		(fp_line
			(start 0.254 -1.016)
			(end -0.508 -1.016)
			(stroke
				(width 0.0254)
				(type default)
			)
			(layer "B.Fab")
		)
		(fp_line
			(start 0.508 -1.016)
			(end 0.254 -1.016)
			(stroke
				(width 0.0254)
				(type default)
			)
			(layer "B.Fab")
		)
		(fp_line
			(start 0.508 1.016)
			(end 0.508 -1.016)
			(stroke
				(width 0.0254)
				(type default)
			)
			(layer "B.Fab")
		)
		(pad "1" smd custom
			(at 0 -0.500126 180)
			(size 0.127 0.127)
			(layers "B.Cu" "B.Mask" "B.Paste")
			(net "VDD_CORE")
			(options
				(clearance outline)
				(anchor circle)
			)
			(primitives
				(gr_poly
					(pts
						(xy -0.1778 0.254) (xy 0.1778 0.254) (xy 0.254 0.1778) (xy 0.254 -0.1778) (xy 0.1778 -0.254) (xy -0.1778 -0.254)
						(xy -0.254 -0.1778) (xy -0.254 0.1778)
					)
					(width 0)
					(fill yes)
				)
			)
		)
		(pad "2" smd custom
			(at 0 0.500126 180)
			(size 0.127 0.127)
			(layers "B.Cu" "B.Mask" "B.Paste")
			(net "GND")
			(options
				(clearance outline)
				(anchor circle)
			)
			(primitives
				(gr_poly
					(pts
						(xy -0.1778 0.254) (xy 0.1778 0.254) (xy 0.254 0.1778) (xy 0.254 -0.1778) (xy 0.1778 -0.254) (xy -0.1778 -0.254)
						(xy -0.254 -0.1778) (xy -0.254 0.1778)
					)
					(width 0)
					(fill yes)
				)
			)
		)
	)
)
